# T6G (Grand Teton) — schematic netlist excerpt (pin names and nets, part order shuffled) for the footprints in the layout excerpt that follows; sources: Cadence DE-HDL packaged netlist, KiCad conversion of 04192023_DAF0TMB3IC0_F0TG_MB_C_brd_V02_OCP.brd

R1577  Q_RES  49.9 1% CHIP  pkg 0402LF  page 95 : A = I3C_SPD_DDRGL_CPU0_SCL ; B = I3C_SPD_DDRJ_CPU0_SCL
PC6643_2  Q_CAP  22UF 4V 20% X6S  pkg C0805  page 365 : A = P0V9_CPU1_RT_2D ; B = GND
R2917  Q_RES  49.9 1% CHIP  pkg 0402LF  page 130 : A = BMC_MONITER_BUF_R ; B = BMC_MONITER_BUF

(kicad_pcb
	(version 20260206)
	(generator "pcbnew")
	(generator_version "10.0")
	(general
		(thickness 1.6)
		(legacy_teardrops no)
	)
	(paper "A4")
	(title_block
		(title "04192023_DAF0TMB3IC0_F0TG_MB_C_brd_V02_OCP.brd")
		(comment 1 "Grand Teton / footprints 7847-7849 of 8354")
	)
	(layers
		(0 "F.Cu" signal "TOP")
		(4 "In1.Cu" signal "GND")
		(6 "In2.Cu" signal "IN1")
		(8 "In3.Cu" signal "GND1")
		(10 "In4.Cu" signal "IN2")
		(12 "In5.Cu" signal "GND2")
		(14 "In6.Cu" signal "IN3")
		(16 "In7.Cu" signal "GND3")
		(18 "In8.Cu" signal "VCC")
		(20 "In9.Cu" signal "VCC1")
		(22 "In10.Cu" signal "GND4")
		(24 "In11.Cu" signal "IN4")
		(26 "In12.Cu" signal "GND5")
		(28 "In13.Cu" signal "IN5")
		(30 "In14.Cu" signal "GND6")
		(32 "In15.Cu" signal "IN6")
		(34 "In16.Cu" signal "GND7")
		(2 "B.Cu" signal "BOTTOM")
		(9 "F.Adhes" user "F.Adhesive")
		(11 "B.Adhes" user "B.Adhesive")
		(13 "F.Paste" user "Package Geometry/Pastemask Top")
		(15 "B.Paste" user "Package Geometry/Pastemask Bottom")
		(5 "F.SilkS" user "Ref Des/Silkscreen Top")
		(7 "B.SilkS" user "Ref Des/Silkscreen Bottom")
		(1 "F.Mask" user "Board Geometry/Soldermask Top")
		(3 "B.Mask" user "Board Geometry/Soldermask Bottom")
		(17 "Dwgs.User" user "User.Drawings")
		(19 "Cmts.User" user "User.Comments")
		(21 "Eco1.User" user "User.Eco1")
		(23 "Eco2.User" user "User.Eco2")
		(25 "Edge.Cuts" user "Board Geometry/Outline")
		(27 "Margin" user)
		(31 "F.CrtYd" user "Package Geometry/Place Bound Top")
		(29 "B.CrtYd" user "Package Geometry/Place Bound Bottom")
		(35 "F.Fab" user "Ref Des/Assembly Top")
		(33 "B.Fab" user "Ref Des/Assembly Bottom")
	)
	(footprint ""
		(layer "B.Cu")
		(at 182.801768 -413.743394 180)
		(property "Reference" "R2917"
			(at 0 0 0)
			(layer "B.SilkS")
			(hide yes)
			(effects
				(font
					(size 1.27 1.27)
				)
				(justify mirror)
			)
		)
		(property "Value" ""
			(at 0 0 0)
			(layer "B.Fab")
			(effects
				(font
					(size 1.27 1.27)
				)
				(justify mirror)
			)
		)
		(duplicate_pad_numbers_are_jumpers no)
		(fp_line
			(start 0.7874 0.4064)
			(end 0.7874 -0.4064)
			(stroke
				(width 0.1524)
				(type default)
			)
			(layer "B.SilkS")
		)
		(fp_line
			(start 0.7874 -0.4064)
			(end -0.7874 -0.4064)
			(stroke
				(width 0.1524)
				(type default)
			)
			(layer "B.SilkS")
		)
		(fp_line
			(start -0.7874 0.4064)
			(end 0.7874 0.4064)
			(stroke
				(width 0.1524)
				(type default)
			)
			(layer "B.SilkS")
		)
		(fp_line
			(start -0.7874 -0.4064)
			(end -0.7874 0.4064)
			(stroke
				(width 0.1524)
				(type default)
			)
			(layer "B.SilkS")
		)
		(fp_line
			(start 0.67945 0.3048)
			(end 0.67945 -0.305054)
			(stroke
				(width 0.1)
				(type default)
			)
			(layer "B.Fab")
		)
		(fp_line
			(start 0.67945 -0.305054)
			(end 0.12065 -0.305054)
			(stroke
				(width 0.1)
				(type default)
			)
			(layer "B.Fab")
		)
		(fp_line
			(start 0.12065 0.3048)
			(end 0.67945 0.3048)
			(stroke
				(width 0.1)
				(type default)
			)
			(layer "B.Fab")
		)
		(fp_line
			(start 0.12065 0.2794)
			(end 0.12065 0.3048)
			(stroke
				(width 0.1)
				(type default)
			)
			(layer "B.Fab")
		)
		(fp_line
			(start 0.12065 -0.2794)
			(end -0.12065 -0.2794)
			(stroke
				(width 0.1)
				(type default)
			)
			(layer "B.Fab")
		)
		(fp_line
			(start 0.12065 -0.305054)
			(end 0.12065 -0.2794)
			(stroke
				(width 0.1)
				(type default)
			)
			(layer "B.Fab")
		)
		(fp_line
			(start -0.120396 0.3048)
			(end -0.120396 0.2794)
			(stroke
				(width 0.1)
				(type default)
			)
			(layer "B.Fab")
		)
		(fp_line
			(start -0.120396 0.2794)
			(end 0.12065 0.2794)
			(stroke
				(width 0.1)
				(type default)
			)
			(layer "B.Fab")
		)
		(fp_line
			(start -0.12065 -0.2794)
			(end -0.12065 -0.3048)
			(stroke
				(width 0.1)
				(type default)
			)
			(layer "B.Fab")
		)
		(fp_line
			(start -0.12065 -0.3048)
			(end -0.67945 -0.3048)
			(stroke
				(width 0.1)
				(type default)
			)
			(layer "B.Fab")
		)
		(fp_line
			(start -0.67945 0.3048)
			(end -0.120396 0.3048)
			(stroke
				(width 0.1)
				(type default)
			)
			(layer "B.Fab")
		)
		(fp_line
			(start -0.67945 -0.3048)
			(end -0.67945 0.3048)
			(stroke
				(width 0.1)
				(type default)
			)
			(layer "B.Fab")
		)
		(pad "1" smd circle
			(at 0.40005 0)
			(size 0 0)
			(layers "B.Cu" "B.Mask" "B.Paste")
			(net "BMC_MONITER_BUF_R")
		)
		(pad "2" smd circle
			(at -0.40005 0)
			(size 0 0)
			(layers "B.Cu" "B.Mask" "B.Paste")
			(net "BMC_MONITER_BUF")
		)
	)
	(footprint ""
		(layer "B.Cu")
		(at 19.748246 -383.038096 -90)
		(property "Reference" "PC6643_2"
			(at 0 0 90)
			(layer "B.SilkS")
			(hide yes)
			(effects
				(font
					(size 1.27 1.27)
				)
				(justify mirror)
			)
		)
		(property "Value" ""
			(at 0 0 90)
			(layer "B.Fab")
			(effects
				(font
					(size 1.27 1.27)
				)
				(justify mirror)
			)
		)
		(duplicate_pad_numbers_are_jumpers no)
		(fp_line
			(start -1.524 0.762)
			(end 1.524 0.762)
			(stroke
				(width 0.1524)
				(type default)
			)
			(layer "B.SilkS")
		)
		(fp_line
			(start 1.524 0.762)
			(end 1.524 -0.762)
			(stroke
				(width 0.1524)
				(type default)
			)
			(layer "B.SilkS")
		)
		(fp_line
			(start -1.524 -0.762)
			(end -1.524 0.762)
			(stroke
				(width 0.1524)
				(type default)
			)
			(layer "B.SilkS")
		)
		(fp_line
			(start 1.524 -0.762)
			(end -1.524 -0.762)
			(stroke
				(width 0.1524)
				(type default)
			)
			(layer "B.SilkS")
		)
		(fp_line
			(start -1.1049 0.724916)
			(end -1.1049 -0.724916)
			(stroke
				(width 0.1)
				(type default)
			)
			(layer "B.Fab")
		)
		(fp_line
			(start 1.1049 0.724916)
			(end -1.1049 0.724916)
			(stroke
				(width 0.1)
				(type default)
			)
			(layer "B.Fab")
		)
		(fp_line
			(start -1.1049 -0.724916)
			(end 1.1049 -0.724916)
			(stroke
				(width 0.1)
				(type default)
			)
			(layer "B.Fab")
		)
		(fp_line
			(start 1.1049 -0.724916)
			(end 1.1049 0.724916)
			(stroke
				(width 0.1)
				(type default)
			)
			(layer "B.Fab")
		)
		(pad "1" smd rect
			(at 0.889 0 270)
			(size 1.016 1.27)
			(layers "B.Cu" "B.Mask" "B.Paste")
			(net "P0V9_CPU1_RT_2D")
		)
		(pad "2" smd rect
			(at -0.889 0 270)
			(size 1.016 1.27)
			(layers "B.Cu" "B.Mask" "B.Paste")
			(net "GND")
		)
	)
	(footprint ""
		(layer "B.Cu")
		(at 438.344564 -194.893946 180)
		(property "Reference" "R1577"
			(at 0 0 0)
			(layer "B.SilkS")
			(hide yes)
			(effects
				(font
					(size 1.27 1.27)
				)
				(justify mirror)
			)
		)
		(property "Value" ""
			(at 0 0 0)
			(layer "B.Fab")
			(effects
				(font
					(size 1.27 1.27)
				)
				(justify mirror)
			)
		)
		(duplicate_pad_numbers_are_jumpers no)
		(fp_line
			(start 0.7874 0.4064)
			(end 0.7874 -0.4064)
			(stroke
				(width 0.1524)
				(type default)
			)
			(layer "B.SilkS")
		)
		(fp_line
			(start 0.7874 -0.4064)
			(end -0.7874 -0.4064)
			(stroke
				(width 0.1524)
				(type default)
			)
			(layer "B.SilkS")
		)
		(fp_line
			(start -0.7874 0.4064)
			(end 0.7874 0.4064)
			(stroke
				(width 0.1524)
				(type default)
			)
			(layer "B.SilkS")
		)
		(fp_line
			(start -0.7874 -0.4064)
			(end -0.7874 0.4064)
			(stroke
				(width 0.1524)
				(type default)
			)
			(layer "B.SilkS")
		)
		(fp_line
			(start 0.67945 0.3048)
			(end 0.67945 -0.305054)
			(stroke
				(width 0.1)
				(type default)
			)
			(layer "B.Fab")
		)
		(fp_line
			(start 0.67945 -0.305054)
			(end 0.12065 -0.305054)
			(stroke
				(width 0.1)
				(type default)
			)
			(layer "B.Fab")
		)
		(fp_line
			(start 0.12065 0.3048)
			(end 0.67945 0.3048)
			(stroke
				(width 0.1)
				(type default)
			)
			(layer "B.Fab")
		)
		(fp_line
			(start 0.12065 0.2794)
			(end 0.12065 0.3048)
			(stroke
				(width 0.1)
				(type default)
			)
			(layer "B.Fab")
		)
		(fp_line
			(start 0.12065 -0.2794)
			(end -0.12065 -0.2794)
			(stroke
				(width 0.1)
				(type default)
			)
			(layer "B.Fab")
		)
		(fp_line
			(start 0.12065 -0.305054)
			(end 0.12065 -0.2794)
			(stroke
				(width 0.1)
				(type default)
			)
			(layer "B.Fab")
		)
		(fp_line
			(start -0.120396 0.3048)
			(end -0.120396 0.2794)
			(stroke
				(width 0.1)
				(type default)
			)
			(layer "B.Fab")
		)
		(fp_line
			(start -0.120396 0.2794)
			(end 0.12065 0.2794)
			(stroke
				(width 0.1)
				(type default)
			)
			(layer "B.Fab")
		)
		(fp_line
			(start -0.12065 -0.2794)
			(end -0.12065 -0.3048)
			(stroke
				(width 0.1)
				(type default)
			)
			(layer "B.Fab")
		)
		(fp_line
			(start -0.12065 -0.3048)
			(end -0.67945 -0.3048)
			(stroke
				(width 0.1)
				(type default)
			)
			(layer "B.Fab")
		)
		(fp_line
			(start -0.67945 0.3048)
			(end -0.120396 0.3048)
			(stroke
				(width 0.1)
				(type default)
			)
			(layer "B.Fab")
		)
		(fp_line
			(start -0.67945 -0.3048)
			(end -0.67945 0.3048)
			(stroke
				(width 0.1)
				(type default)
			)
			(layer "B.Fab")
		)
		(pad "1" smd circle
			(at 0.40005 0)
			(size 0 0)
			(layers "B.Cu" "B.Mask" "B.Paste")
			(net "I3C_SPD_DDRGL_CPU0_SCL")
		)
		(pad "2" smd circle
			(at -0.40005 0)
			(size 0 0)
			(layers "B.Cu" "B.Mask" "B.Paste")
			(net "I3C_SPD_DDRJ_CPU0_SCL")
		)
	)
)
